(kicad_pcb
	(version 20260206)
	(generator "pcbnew")
	(generator_version "10.0")
	(general
		(thickness 1.6)
		(legacy_teardrops no)
	)
	(paper "A4")
	(title_block
		(title "Bryce Canyon_IOM_M2_16342-2_OCP.brd")
		(comment 1 "Bryce Canyon / footprints 669-674 of 1146")
	)
	(layers
		(0 "F.Cu" signal "TOP")
		(4 "In1.Cu" signal "L2GND")
		(6 "In2.Cu" signal "L3")
		(8 "In3.Cu" signal "L4VCC")
		(10 "In4.Cu" signal "L5VCC")
		(12 "In5.Cu" signal "L6")
		(14 "In6.Cu" signal "L7GND")
		(2 "B.Cu" signal "BOTTOM")
		(9 "F.Adhes" user "F.Adhesive")
		(11 "B.Adhes" user "B.Adhesive")
		(13 "F.Paste" user "Package Geometry/Pastemask Top")
		(15 "B.Paste" user "Package Geometry/Pastemask Bottom")
		(5 "F.SilkS" user "Ref Des/Silkscreen Top")
		(7 "B.SilkS" user "Ref Des/Silkscreen Bottom")
		(1 "F.Mask" user "Board Geometry/Soldermask Top")
		(3 "B.Mask" user "Board Geometry/Soldermask Bottom")
		(17 "Dwgs.User" user "User.Drawings")
		(19 "Cmts.User" user "User.Comments")
		(21 "Eco1.User" user "User.Eco1")
		(23 "Eco2.User" user "User.Eco2")
		(25 "Edge.Cuts" user "Board Geometry/Outline")
		(27 "Margin" user)
		(31 "F.CrtYd" user "Package Geometry/Place Bound Top")
		(29 "B.CrtYd" user "Package Geometry/Place Bound Bottom")
		(35 "F.Fab" user "Ref Des/Assembly Top")
		(33 "B.Fab" user "Ref Des/Assembly Bottom")
	)
	(footprint ""
		(layer "F.Cu")
		(at 60.9092 -121.3612 -90)
		(property "Reference" "SKT2"
			(at 0 0 270)
			(layer "F.SilkS")
			(hide yes)
			(effects
				(font
					(size 1.27 1.27)
				)
			)
		)
		(property "Value" "SKT-SPI16P-GP-U"
			(at -8.9916 4.641596 270)
			(unlocked yes)
			(layer "F.Fab")
			(hide yes)
			(effects
				(font
					(size 1.016 1.016)
					(thickness 0.1524)
				)
			)
		)
		(property "Device Type" "SKT-SOIC16-153139H258"
			(at -8.9916 3.117596 270)
			(unlocked yes)
			(layer "F.Fab")
			(hide yes)
			(effects
				(font
					(size 1.016 1.016)
					(thickness 0.1524)
				)
			)
		)
		(duplicate_pad_numbers_are_jumpers no)
		(fp_line
			(start -7.8994 6.4008)
			(end 7.8994 6.4008)
			(stroke
				(width 0.1524)
				(type default)
			)
			(layer "F.SilkS")
		)
		(fp_line
			(start 7.8994 6.4008)
			(end 7.8994 -6.4008)
			(stroke
				(width 0.1524)
				(type default)
			)
			(layer "F.SilkS")
		)
		(fp_line
			(start 6.7183 0.0762)
			(end 7.8994 1.2573)
			(stroke
				(width 0.1524)
				(type default)
			)
			(layer "F.SilkS")
		)
		(fp_line
			(start 7.8867 -1.0922)
			(end 6.7183 0.0762)
			(stroke
				(width 0.1524)
				(type default)
			)
			(layer "F.SilkS")
		)
		(fp_line
			(start 7.7216 -6.223)
			(end 7.7216 -3.6576)
			(stroke
				(width 0.508)
				(type default)
			)
			(layer "F.SilkS")
		)
		(fp_line
			(start -7.8994 -6.4008)
			(end -7.8994 6.4008)
			(stroke
				(width 0.1524)
				(type default)
			)
			(layer "F.SilkS")
		)
		(fp_line
			(start 7.8994 -6.4008)
			(end -7.8994 -6.4008)
			(stroke
				(width 0.1524)
				(type default)
			)
			(layer "F.SilkS")
		)
		(fp_poly
			(pts
				(xy -4.699 -3.855466) (xy -4.699 3.855466) (xy 4.699 3.855466) (xy 4.699 -3.855466)
			)
			(stroke
				(width 0)
				(type default)
			)
			(fill yes)
			(layer "F.SilkS")
		)
		(fp_rect
			(start -8.1534 11.6078)
			(end 8.1534 6.4008)
			(stroke
				(width 0)
				(type default)
			)
			(fill no)
			(layer "F.CrtYd")
		)
		(fp_rect
			(start -8.1534 -6.4008)
			(end 8.1534 -12.5222)
			(stroke
				(width 0)
				(type default)
			)
			(fill no)
			(layer "F.CrtYd")
		)
		(fp_poly
			(pts
				(xy -8.1534 6.4008) (xy -8.1534 -6.4008) (xy -6.2484 -6.4008) (xy -6.2484 -2.6416) (xy -7.6454 -2.6416)
				(xy -7.6454 2.6416) (xy -6.2484 2.6416) (xy -6.2484 6.4008)
			)
			(stroke
				(width 0)
				(type default)
			)
			(fill no)
			(layer "F.CrtYd")
		)
		(fp_poly
			(pts
				(xy 6.2484 -6.4008) (xy 8.1534 -6.4008) (xy 8.1534 6.4008) (xy 6.2484 6.4008) (xy 6.2484 2.6416)
				(xy 7.6454 2.6416) (xy 7.6454 -2.6416) (xy 6.2484 -2.6416)
			)
			(stroke
				(width 0)
				(type default)
			)
			(fill no)
			(layer "F.CrtYd")
		)
		(fp_poly
			(pts
				(xy 6.2484 -6.4008) (xy -6.2484 -6.4008) (xy -6.2484 -2.6416) (xy -7.6454 -2.6416) (xy -7.6454 2.6416)
				(xy -6.2484 2.6416) (xy -6.2484 6.4008) (xy 6.2484 6.4008) (xy 6.2484 2.6416) (xy 7.6454 2.6416)
				(xy 7.6454 -2.6416) (xy 6.2484 -2.6416)
			)
			(stroke
				(width 0)
				(type default)
			)
			(fill no)
			(layer "F.CrtYd")
		)
		(fp_rect
			(start -8.1534 11.6078)
			(end 8.1534 -12.5222)
			(stroke
				(width 0)
				(type default)
			)
			(fill no)
			(layer "F.Fab")
		)
		(pad "1" smd rect
			(at 4.445 -4.896866 270)
			(size 0.508 1.6764)
			(layers "F.Cu" "F.Mask" "F.Paste")
			(net "PU_IBMC_BT_HOLD_N")
		)
		(pad "2" smd rect
			(at 3.175 -4.896866 270)
			(size 0.508 1.6764)
			(layers "F.Cu" "F.Mask" "F.Paste")
			(net "P3V3_STBY")
		)
		(pad "3" smd rect
			(at 1.905 -4.896866 270)
			(size 0.508 1.6764)
			(layers "F.Cu" "F.Mask" "F.Paste")
			(net "FLA1_SPI_RST")
		)
		(pad "4" smd rect
			(at 0.635 -4.896866 270)
			(size 0.508 1.6764)
			(layers "F.Cu" "F.Mask" "F.Paste")
			(net "Net_583")
		)
		(pad "5" smd rect
			(at -0.635 -4.896866 270)
			(size 0.508 1.6764)
			(layers "F.Cu" "F.Mask" "F.Paste")
			(net "Net_582")
		)
		(pad "6" smd rect
			(at -1.905 -4.896866 270)
			(size 0.508 1.6764)
			(layers "F.Cu" "F.Mask" "F.Paste")
			(net "Net_581")
		)
		(pad "7" smd rect
			(at -3.175 -4.896866 270)
			(size 0.508 1.6764)
			(layers "F.Cu" "F.Mask" "F.Paste")
			(net "FLA_CS_1_R")
		)
		(pad "8" smd rect
			(at -4.445 -4.896866 270)
			(size 0.508 1.6764)
			(layers "F.Cu" "F.Mask" "F.Paste")
			(net "BMC_SPI_MISO_R")
		)
		(pad "9" smd rect
			(at -4.445 4.896866 270)
			(size 0.508 1.6764)
			(layers "F.Cu" "F.Mask" "F.Paste")
			(net "FLA1_WP_N")
		)
		(pad "10" smd rect
			(at -3.175 4.896866 270)
			(size 0.508 1.6764)
			(layers "F.Cu" "F.Mask" "F.Paste")
			(net "GND")
		)
		(pad "11" smd rect
			(at -1.905 4.896866 270)
			(size 0.508 1.6764)
			(layers "F.Cu" "F.Mask" "F.Paste")
			(net "Net_587")
		)
		(pad "12" smd rect
			(at -0.635 4.896866 270)
			(size 0.508 1.6764)
			(layers "F.Cu" "F.Mask" "F.Paste")
			(net "Net_586")
		)
		(pad "13" smd rect
			(at 0.635 4.896866 270)
			(size 0.508 1.6764)
			(layers "F.Cu" "F.Mask" "F.Paste")
			(net "Net_585")
		)
		(pad "14" smd rect
			(at 1.905 4.896866 270)
			(size 0.508 1.6764)
			(layers "F.Cu" "F.Mask" "F.Paste")
			(net "Net_584")
		)
		(pad "15" smd rect
			(at 3.175 4.896866 270)
			(size 0.508 1.6764)
			(layers "F.Cu" "F.Mask" "F.Paste")
			(net "BMC_SPI_MOSI_R")
		)
		(pad "16" smd rect
			(at 4.445 4.896866 270)
			(size 0.508 1.6764)
			(layers "F.Cu" "F.Mask" "F.Paste")
			(net "BMC_SPI_CLK_R")
		)
	)
	(footprint ""
		(layer "F.Cu")
		(at 63.9826 -156.2354)
		(property "Reference" "R382"
			(at 0 0 0)
			(layer "F.SilkS")
			(hide yes)
			(effects
				(font
					(size 1.27 1.27)
				)
			)
		)
		(property "Value" "4K7R2F-GP"
			(at 0.064008 -3.993896 0)
			(unlocked yes)
			(layer "F.Fab")
			(hide yes)
			(effects
				(font
					(size 1.016 1.016)
					(thickness 0.1524)
				)
			)
		)
		(property "Device Type" "R402H16"
			(at 0.064008 -5.517896 0)
			(unlocked yes)
			(layer "F.Fab")
			(hide yes)
			(effects
				(font
					(size 1.016 1.016)
					(thickness 0.1524)
				)
			)
		)
		(duplicate_pad_numbers_are_jumpers no)
		(fp_line
			(start -0.508 -0.9398)
			(end -0.508 0.9398)
			(stroke
				(width 0.1524)
				(type default)
			)
			(layer "F.SilkS")
		)
		(fp_line
			(start 0.508 -0.9398)
			(end -0.508 -0.9398)
			(stroke
				(width 0.1524)
				(type default)
			)
			(layer "F.SilkS")
		)
		(fp_rect
			(start -0.508 0.9398)
			(end 0.508 -0.9398)
			(stroke
				(width 0)
				(type default)
			)
			(fill no)
			(layer "F.CrtYd")
		)
		(fp_rect
			(start -0.508 0.9398)
			(end 0.508 -0.9398)
			(stroke
				(width 0)
				(type default)
			)
			(fill no)
			(layer "F.Fab")
		)
		(pad "1" smd custom
			(at 0 -0.4445)
			(size 0.1397 0.1397)
			(layers "F.Cu" "F.Mask" "F.Paste")
			(net "P3V3_STBY")
			(options
				(clearance outline)
				(anchor circle)
			)
			(primitives
				(gr_poly
					(pts
						(arc
							(start -0.1778 -0.2794)
							(mid -0.249642 -0.249642)
							(end -0.2794 -0.1778)
						)
						(arc
							(start -0.2794 0.1778)
							(mid -0.249642 0.249642)
							(end -0.1778 0.2794)
						)
						(arc
							(start 0.1778 0.2794)
							(mid 0.249642 0.249642)
							(end 0.2794 0.1778)
						)
						(arc
							(start 0.2794 -0.1778)
							(mid 0.249642 -0.249642)
							(end 0.1778 -0.2794)
						)
					)
					(width 0)
					(fill yes)
				)
			)
		)
		(pad "2" smd custom
			(at 0 0.4445)
			(size 0.1397 0.1397)
			(layers "F.Cu" "F.Mask" "F.Paste")
			(net "NCSI_TXD1")
			(options
				(clearance outline)
				(anchor circle)
			)
			(primitives
				(gr_poly
					(pts
						(arc
							(start -0.1778 -0.2794)
							(mid -0.249642 -0.249642)
							(end -0.2794 -0.1778)
						)
						(arc
							(start -0.2794 0.1778)
							(mid -0.249642 0.249642)
							(end -0.1778 0.2794)
						)
						(arc
							(start 0.1778 0.2794)
							(mid 0.249642 0.249642)
							(end 0.2794 0.1778)
						)
						(arc
							(start 0.2794 -0.1778)
							(mid 0.249642 -0.249642)
							(end 0.1778 -0.2794)
						)
					)
					(width 0)
					(fill yes)
				)
			)
		)
	)
	(footprint ""
		(layer "F.Cu")
		(at 21.023072 -15.68577)
		(property "Reference" "D2"
			(at 0 0 0)
			(layer "F.SilkS")
			(hide yes)
			(effects
				(font
					(size 1.27 1.27)
				)
			)
		)
		(property "Value" "PESD5V0X1UAB-GP"
			(at 0 -4.690618 0)
			(unlocked yes)
			(layer "F.Fab")
			(hide yes)
			(effects
				(font
					(size 1.016 1.016)
					(thickness 0.1524)
				)
			)
		)
		(property "Device Type" "SOD523AKH26"
			(at 0 -6.214618 0)
			(unlocked yes)
			(layer "F.Fab")
			(hide yes)
			(effects
				(font
					(size 1.016 1.016)
					(thickness 0.1524)
				)
			)
		)
		(duplicate_pad_numbers_are_jumpers no)
		(fp_line
			(start -0.5334 -1.4478)
			(end 0.5334 -1.4478)
			(stroke
				(width 0.1524)
				(type default)
			)
			(layer "F.SilkS")
		)
		(fp_line
			(start -0.5334 1.524)
			(end -0.5334 -1.4478)
			(stroke
				(width 0.1524)
				(type default)
			)
			(layer "F.SilkS")
		)
		(fp_line
			(start 0.4064 1.651)
			(end -0.4064 1.651)
			(stroke
				(width 0.4064)
				(type default)
			)
			(layer "F.SilkS")
		)
		(fp_line
			(start 0.5334 -1.4478)
			(end 0.5334 1.524)
			(stroke
				(width 0.1524)
				(type default)
			)
			(layer "F.SilkS")
		)
		(fp_line
			(start 0.5334 1.524)
			(end -0.5334 1.524)
			(stroke
				(width 0.1524)
				(type default)
			)
			(layer "F.SilkS")
		)
		(fp_rect
			(start -0.6096 1.8542)
			(end 0.6096 -1.524)
			(stroke
				(width 0)
				(type default)
			)
			(fill no)
			(layer "F.CrtYd")
		)
		(fp_poly
			(pts
				(xy -0.6096 -1.524) (xy 0.6096 -1.524) (xy 0.6096 1.8542) (xy -0.6096 1.8542)
			)
			(stroke
				(width 0)
				(type default)
			)
			(fill no)
			(layer "F.Fab")
		)
		(pad "A" smd rect
			(at 0 -0.762)
			(size 0.5588 1.016)
			(layers "F.Cu" "F.Mask" "F.Paste")
			(net "GND")
		)
		(pad "K" smd rect
			(at 0 0.762)
			(size 0.5588 1.016)
			(layers "F.Cu" "F.Mask" "F.Paste")
			(net "FP_PWR_BTN_N")
		)
	)
	(footprint ""
		(layer "F.Cu")
		(at 151.013414 -7.945374)
		(property "Reference" "R522"
			(at 0 0 0)
			(layer "F.SilkS")
			(hide yes)
			(effects
				(font
					(size 1.27 1.27)
				)
			)
		)
		(property "Value" "0R2J-2-GP"
			(at 0.064008 -3.993896 0)
			(unlocked yes)
			(layer "F.Fab")
			(hide yes)
			(effects
				(font
					(size 1.016 1.016)
					(thickness 0.1524)
				)
			)
		)
		(property "Device Type" "R402H16"
			(at 0.064008 -5.517896 0)
			(unlocked yes)
			(layer "F.Fab")
			(hide yes)
			(effects
				(font
					(size 1.016 1.016)
					(thickness 0.1524)
				)
			)
		)
		(duplicate_pad_numbers_are_jumpers no)
		(fp_line
			(start -0.508 -0.9398)
			(end -0.508 0.9398)
			(stroke
				(width 0.1524)
				(type default)
			)
			(layer "F.SilkS")
		)
		(fp_line
			(start 0.508 -0.9398)
			(end -0.508 -0.9398)
			(stroke
				(width 0.1524)
				(type default)
			)
			(layer "F.SilkS")
		)
		(fp_rect
			(start -0.508 0.9398)
			(end 0.508 -0.9398)
			(stroke
				(width 0)
				(type default)
			)
			(fill no)
			(layer "F.CrtYd")
		)
		(fp_rect
			(start -0.508 0.9398)
			(end 0.508 -0.9398)
			(stroke
				(width 0)
				(type default)
			)
			(fill no)
			(layer "F.Fab")
		)
		(pad "1" smd custom
			(at 0 -0.4445)
			(size 0.1397 0.1397)
			(layers "F.Cu" "F.Mask" "F.Paste")
			(net "P1V8_STBY_EN_R")
			(options
				(clearance outline)
				(anchor circle)
			)
			(primitives
				(gr_poly
					(pts
						(arc
							(start -0.1778 -0.2794)
							(mid -0.249642 -0.249642)
							(end -0.2794 -0.1778)
						)
						(arc
							(start -0.2794 0.1778)
							(mid -0.249642 0.249642)
							(end -0.1778 0.2794)
						)
						(arc
							(start 0.1778 0.2794)
							(mid 0.249642 0.249642)
							(end 0.2794 0.1778)
						)
						(arc
							(start 0.2794 -0.1778)
							(mid 0.249642 -0.249642)
							(end 0.1778 -0.2794)
						)
					)
					(width 0)
					(fill yes)
				)
			)
		)
		(pad "2" smd custom
			(at 0 0.4445)
			(size 0.1397 0.1397)
			(layers "F.Cu" "F.Mask" "F.Paste")
			(net "PWRGD_P2V5_STBY")
			(options
				(clearance outline)
				(anchor circle)
			)
			(primitives
				(gr_poly
					(pts
						(arc
							(start -0.1778 -0.2794)
							(mid -0.249642 -0.249642)
							(end -0.2794 -0.1778)
						)
						(arc
							(start -0.2794 0.1778)
							(mid -0.249642 0.249642)
							(end -0.1778 0.2794)
						)
						(arc
							(start 0.1778 0.2794)
							(mid 0.249642 0.249642)
							(end 0.2794 0.1778)
						)
						(arc
							(start 0.2794 -0.1778)
							(mid 0.249642 -0.249642)
							(end 0.1778 -0.2794)
						)
					)
					(width 0)
					(fill yes)
				)
			)
		)
	)
	(footprint ""
		(layer "F.Cu")
		(at 96.2152 -147.8534 180)
		(property "Reference" "R34"
			(at 0 0 180)
			(layer "F.SilkS")
			(hide yes)
			(effects
				(font
					(size 1.27 1.27)
				)
			)
		)
		(property "Value" "4K7R2F-GP"
			(at 0.064008 -3.993896 180)
			(unlocked yes)
			(layer "F.Fab")
			(hide yes)
			(effects
				(font
					(size 1.016 1.016)
					(thickness 0.1524)
				)
			)
		)
		(property "Device Type" "R402H16"
			(at 0.064008 -5.517896 180)
			(unlocked yes)
			(layer "F.Fab")
			(hide yes)
			(effects
				(font
					(size 1.016 1.016)
					(thickness 0.1524)
				)
			)
		)
		(duplicate_pad_numbers_are_jumpers no)
		(fp_line
			(start 0.508 -0.9398)
			(end -0.508 -0.9398)
			(stroke
				(width 0.1524)
				(type default)
			)
			(layer "F.SilkS")
		)
		(fp_line
			(start -0.508 -0.9398)
			(end -0.508 0.9398)
			(stroke
				(width 0.1524)
				(type default)
			)
			(layer "F.SilkS")
		)
		(fp_rect
			(start -0.508 0.9398)
			(end 0.508 -0.9398)
			(stroke
				(width 0)
				(type default)
			)
			(fill no)
			(layer "F.CrtYd")
		)
		(fp_rect
			(start -0.508 0.9398)
			(end 0.508 -0.9398)
			(stroke
				(width 0)
				(type default)
			)
			(fill no)
			(layer "F.Fab")
		)
		(pad "1" smd custom
			(at 0 -0.4445 180)
			(size 0.1397 0.1397)
			(layers "F.Cu" "F.Mask" "F.Paste")
			(net "P3V3_STBY")
			(options
				(clearance outline)
				(anchor circle)
			)
			(primitives
				(gr_poly
					(pts
						(arc
							(start -0.1778 -0.2794)
							(mid -0.249642 -0.249642)
							(end -0.2794 -0.1778)
						)
						(arc
							(start -0.2794 0.1778)
							(mid -0.249642 0.249642)
							(end -0.1778 0.2794)
						)
						(arc
							(start 0.1778 0.2794)
							(mid 0.249642 0.249642)
							(end 0.2794 0.1778)
						)
						(arc
							(start 0.2794 -0.1778)
							(mid 0.249642 -0.249642)
							(end 0.1778 -0.2794)
						)
					)
					(width 0)
					(fill yes)
				)
			)
		)
		(pad "2" smd custom
			(at 0 0.4445 180)
			(size 0.1397 0.1397)
			(layers "F.Cu" "F.Mask" "F.Paste")
			(net "USB_EN_2")
			(options
				(clearance outline)
				(anchor circle)
			)
			(primitives
				(gr_poly
					(pts
						(arc
							(start -0.1778 -0.2794)
							(mid -0.249642 -0.249642)
							(end -0.2794 -0.1778)
						)
						(arc
							(start -0.2794 0.1778)
							(mid -0.249642 0.249642)
							(end -0.1778 0.2794)
						)
						(arc
							(start 0.1778 0.2794)
							(mid 0.249642 0.249642)
							(end 0.2794 0.1778)
						)
						(arc
							(start 0.2794 -0.1778)
							(mid 0.249642 -0.249642)
							(end 0.1778 -0.2794)
						)
					)
					(width 0)
					(fill yes)
				)
			)
		)
	)
	(footprint ""
		(layer "F.Cu")
		(at 87.884 -147.574 -90)
		(property "Reference" "R422"
			(at 0 0 270)
			(layer "F.SilkS")
			(hide yes)
			(effects
				(font
					(size 1.27 1.27)
				)
			)
		)
		(property "Value" "4K7R2F-GP"
			(at 0.064008 -3.993896 270)
			(unlocked yes)
			(layer "F.Fab")
			(hide yes)
			(effects
				(font
					(size 1.016 1.016)
					(thickness 0.1524)
				)
			)
		)
		(property "Device Type" "R402H16"
			(at 0.064008 -5.517896 270)
			(unlocked yes)
			(layer "F.Fab")
			(hide yes)
			(effects
				(font
					(size 1.016 1.016)
					(thickness 0.1524)
				)
			)
		)
		(duplicate_pad_numbers_are_jumpers no)
		(fp_line
			(start -0.508 -0.9398)
			(end -0.508 0.9398)
			(stroke
				(width 0.1524)
				(type default)
			)
			(layer "F.SilkS")
		)
		(fp_line
			(start 0.508 -0.9398)
			(end -0.508 -0.9398)
			(stroke
				(width 0.1524)
				(type default)
			)
			(layer "F.SilkS")
		)
		(fp_rect
			(start -0.508 0.9398)
			(end 0.508 -0.9398)
			(stroke
				(width 0)
				(type default)
			)
			(fill no)
			(layer "F.CrtYd")
		)
		(fp_rect
			(start -0.508 0.9398)
			(end 0.508 -0.9398)
			(stroke
				(width 0)
				(type default)
			)
			(fill no)
			(layer "F.Fab")
		)
		(pad "1" smd custom
			(at 0 -0.4445 270)
			(size 0.1397 0.1397)
			(layers "F.Cu" "F.Mask" "F.Paste")
			(net "P3V3_STBY")
			(options
				(clearance outline)
				(anchor circle)
			)
			(primitives
				(gr_poly
					(pts
						(arc
							(start -0.1778 -0.2794)
							(mid -0.249642 -0.249642)
							(end -0.2794 -0.1778)
						)
						(arc
							(start -0.2794 0.1778)
							(mid -0.249642 0.249642)
							(end -0.1778 0.2794)
						)
						(arc
							(start 0.1778 0.2794)
							(mid 0.249642 0.249642)
							(end 0.2794 0.1778)
						)
						(arc
							(start 0.2794 -0.1778)
							(mid 0.249642 -0.249642)
							(end 0.1778 -0.2794)
						)
					)
					(width 0)
					(fill yes)
				)
			)
		)
		(pad "2" smd custom
			(at 0 0.4445 270)
			(size 0.1397 0.1397)
			(layers "F.Cu" "F.Mask" "F.Paste")
			(net "IO_EXP0_RESET#_FLT")
			(options
				(clearance outline)
				(anchor circle)
			)
			(primitives
				(gr_poly
					(pts
						(arc
							(start -0.1778 -0.2794)
							(mid -0.249642 -0.249642)
							(end -0.2794 -0.1778)
						)
						(arc
							(start -0.2794 0.1778)
							(mid -0.249642 0.249642)
							(end -0.1778 0.2794)
						)
						(arc
							(start 0.1778 0.2794)
							(mid 0.249642 0.249642)
							(end 0.2794 0.1778)
						)
						(arc
							(start 0.2794 -0.1778)
							(mid 0.249642 -0.249642)
							(end 0.1778 -0.2794)
						)
					)
					(width 0)
					(fill yes)
				)
			)
		)
	)
)
